# SCM (Grand Teton) — schematic netlist excerpt (pin names and nets, part order shuffled) for the footprints in the layout excerpt that follows; sources: Cadence DE-HDL packaged netlist, KiCad conversion of 12092022_DA0F0TMDCD0_F0T_Management_Board_D_brd_V3_OCP.brd

D11  SCHOTTKY_AC  SS0530 IC  pkg SOD123XD  page 23 : A = P5V_AUX ; C = CRT_VCC5
R24  Q_RES  10 1% CHIP  pkg 0402LF  page 15 : A = V_DACB_R ; B = V_DACB

(kicad_pcb
	(version 20260206)
	(generator "pcbnew")
	(generator_version "10.0")
	(general
		(thickness 1.6)
		(legacy_teardrops no)
	)
	(paper "A4")
	(title_block
		(title "12092022_DA0F0TMDCD0_F0T_Management_Board_D_brd_V3_OCP.brd")
		(comment 1 "Grand Teton / footprints 1322-1323 of 1440")
	)
	(layers
		(0 "F.Cu" signal "TOP")
		(4 "In1.Cu" signal "GND")
		(6 "In2.Cu" signal "IN1")
		(8 "In3.Cu" signal "GND1")
		(10 "In4.Cu" signal "IN2")
		(12 "In5.Cu" signal "VCC")
		(14 "In6.Cu" signal "VCC1")
		(16 "In7.Cu" signal "IN3")
		(18 "In8.Cu" signal "GND2")
		(20 "In9.Cu" signal "IN4")
		(22 "In10.Cu" signal "GND3")
		(2 "B.Cu" signal "BOTTOM")
		(9 "F.Adhes" user "F.Adhesive")
		(11 "B.Adhes" user "B.Adhesive")
		(13 "F.Paste" user "Package Geometry/Pastemask Top")
		(15 "B.Paste" user "Package Geometry/Pastemask Bottom")
		(5 "F.SilkS" user "Ref Des/Silkscreen Top")
		(7 "B.SilkS" user "Ref Des/Silkscreen Bottom")
		(1 "F.Mask" user "Board Geometry/Soldermask Top")
		(3 "B.Mask" user "Board Geometry/Soldermask Bottom")
		(17 "Dwgs.User" user "User.Drawings")
		(19 "Cmts.User" user "User.Comments")
		(21 "Eco1.User" user "User.Eco1")
		(23 "Eco2.User" user "User.Eco2")
		(25 "Edge.Cuts" user "Board Geometry/Outline")
		(27 "Margin" user)
		(31 "F.CrtYd" user "Package Geometry/Place Bound Top")
		(29 "B.CrtYd" user "Package Geometry/Place Bound Bottom")
		(35 "F.Fab" user "Ref Des/Assembly Top")
		(33 "B.Fab" user "Ref Des/Assembly Bottom")
	)
	(footprint ""
		(layer "B.Cu")
		(at 45.085 -62.0014 -90)
		(property "Reference" "R24"
			(at 0 0 90)
			(layer "B.SilkS")
			(hide yes)
			(effects
				(font
					(size 1.27 1.27)
				)
				(justify mirror)
			)
		)
		(property "Value" ""
			(at 0 0 90)
			(layer "B.Fab")
			(effects
				(font
					(size 1.27 1.27)
				)
				(justify mirror)
			)
		)
		(duplicate_pad_numbers_are_jumpers no)
		(fp_line
			(start -0.7874 0.4064)
			(end 0.7874 0.4064)
			(stroke
				(width 0.1524)
				(type default)
			)
			(layer "B.SilkS")
		)
		(fp_line
			(start 0.7874 0.4064)
			(end 0.7874 -0.4064)
			(stroke
				(width 0.1524)
				(type default)
			)
			(layer "B.SilkS")
		)
		(fp_line
			(start -0.7874 -0.4064)
			(end -0.7874 0.4064)
			(stroke
				(width 0.1524)
				(type default)
			)
			(layer "B.SilkS")
		)
		(fp_line
			(start 0.7874 -0.4064)
			(end -0.7874 -0.4064)
			(stroke
				(width 0.1524)
				(type default)
			)
			(layer "B.SilkS")
		)
		(fp_line
			(start -0.67945 0.3048)
			(end -0.120396 0.3048)
			(stroke
				(width 0.1)
				(type default)
			)
			(layer "B.Fab")
		)
		(fp_line
			(start -0.120396 0.3048)
			(end -0.120396 0.2794)
			(stroke
				(width 0.1)
				(type default)
			)
			(layer "B.Fab")
		)
		(fp_line
			(start 0.12065 0.3048)
			(end 0.67945 0.3048)
			(stroke
				(width 0.1)
				(type default)
			)
			(layer "B.Fab")
		)
		(fp_line
			(start 0.67945 0.3048)
			(end 0.67945 -0.305054)
			(stroke
				(width 0.1)
				(type default)
			)
			(layer "B.Fab")
		)
		(fp_line
			(start -0.120396 0.2794)
			(end 0.12065 0.2794)
			(stroke
				(width 0.1)
				(type default)
			)
			(layer "B.Fab")
		)
		(fp_line
			(start 0.12065 0.2794)
			(end 0.12065 0.3048)
			(stroke
				(width 0.1)
				(type default)
			)
			(layer "B.Fab")
		)
		(fp_line
			(start -0.12065 -0.2794)
			(end -0.12065 -0.3048)
			(stroke
				(width 0.1)
				(type default)
			)
			(layer "B.Fab")
		)
		(fp_line
			(start 0.12065 -0.2794)
			(end -0.12065 -0.2794)
			(stroke
				(width 0.1)
				(type default)
			)
			(layer "B.Fab")
		)
		(fp_line
			(start -0.67945 -0.3048)
			(end -0.67945 0.3048)
			(stroke
				(width 0.1)
				(type default)
			)
			(layer "B.Fab")
		)
		(fp_line
			(start -0.12065 -0.3048)
			(end -0.67945 -0.3048)
			(stroke
				(width 0.1)
				(type default)
			)
			(layer "B.Fab")
		)
		(fp_line
			(start 0.12065 -0.305054)
			(end 0.12065 -0.2794)
			(stroke
				(width 0.1)
				(type default)
			)
			(layer "B.Fab")
		)
		(fp_line
			(start 0.67945 -0.305054)
			(end 0.12065 -0.305054)
			(stroke
				(width 0.1)
				(type default)
			)
			(layer "B.Fab")
		)
		(pad "1" smd circle
			(at 0.40005 0 90)
			(size 0 0)
			(layers "B.Cu" "B.Mask" "B.Paste")
			(net "V_DACB_R")
		)
		(pad "2" smd circle
			(at -0.40005 0 90)
			(size 0 0)
			(layers "B.Cu" "B.Mask" "B.Paste")
			(net "V_DACB")
		)
	)
	(footprint ""
		(layer "B.Cu")
		(at 31.027624 -37.5412 90)
		(property "Reference" "D11"
			(at -3.7592 -3.977894 270)
			(unlocked yes)
			(layer "B.SilkS")
			(effects
				(font
					(size 0.7874 0.5842)
					(thickness 0.1524)
				)
				(justify left mirror)
			)
		)
		(property "Value" ""
			(at 0 0 90)
			(layer "B.Fab")
			(effects
				(font
					(size 1.27 1.27)
				)
				(justify mirror)
			)
		)
		(duplicate_pad_numbers_are_jumpers no)
		(fp_line
			(start 2.262378 -0.899922)
			(end 2.262378 0.899922)
			(stroke
				(width 0.1524)
				(type default)
			)
			(layer "B.SilkS")
		)
		(fp_line
			(start -2.567178 -0.899922)
			(end 2.262378 -0.899922)
			(stroke
				(width 0.1524)
				(type default)
			)
			(layer "B.SilkS")
		)
		(fp_line
			(start 0.3175 -0.508)
			(end 0.3175 0.508)
			(stroke
				(width 0.1524)
				(type default)
			)
			(layer "B.SilkS")
		)
		(fp_line
			(start -0.3175 -0.508)
			(end -0.3175 0.508)
			(stroke
				(width 0.1524)
				(type default)
			)
			(layer "B.SilkS")
		)
		(fp_line
			(start 0.8255 0)
			(end 0.3175 0)
			(stroke
				(width 0.1524)
				(type default)
			)
			(layer "B.SilkS")
		)
		(fp_line
			(start -0.3175 0)
			(end 0.3175 -0.508)
			(stroke
				(width 0.1524)
				(type default)
			)
			(layer "B.SilkS")
		)
		(fp_line
			(start -0.3175 0)
			(end -0.8255 0)
			(stroke
				(width 0.1524)
				(type default)
			)
			(layer "B.SilkS")
		)
		(fp_line
			(start 0.3175 0.508)
			(end -0.3175 0)
			(stroke
				(width 0.1524)
				(type default)
			)
			(layer "B.SilkS")
		)
		(fp_line
			(start 2.262378 0.899922)
			(end -2.567178 0.899922)
			(stroke
				(width 0.1524)
				(type default)
			)
			(layer "B.SilkS")
		)
		(fp_line
			(start -2.567178 0.899922)
			(end -2.567178 -0.899922)
			(stroke
				(width 0.1524)
				(type default)
			)
			(layer "B.SilkS")
		)
		(fp_poly
			(pts
				(xy -2.567178 -0.899922) (xy -2.186178 -0.899922) (xy -2.186178 0.899922) (xy -2.567178 0.899922)
			)
			(stroke
				(width 0)
				(type default)
			)
			(fill yes)
			(layer "B.SilkS")
		)
		(fp_line
			(start 1.400048 -0.899922)
			(end 1.400048 0.899922)
			(stroke
				(width 0.1)
				(type default)
			)
			(layer "B.Fab")
		)
		(fp_line
			(start -1.400048 -0.899922)
			(end 1.400048 -0.899922)
			(stroke
				(width 0.1)
				(type default)
			)
			(layer "B.Fab")
		)
		(fp_line
			(start 1.400048 0.899922)
			(end -1.400048 0.899922)
			(stroke
				(width 0.1)
				(type default)
			)
			(layer "B.Fab")
		)
		(fp_line
			(start -1.400048 0.899922)
			(end -1.400048 -0.899922)
			(stroke
				(width 0.1)
				(type default)
			)
			(layer "B.Fab")
		)
		(fp_text user "+"
			(at 1.938274 -0.618236 270)
			(unlocked yes)
			(layer "B.SilkS")
			(effects
				(font
					(size 1.905 1.4224)
					(thickness 0.1524)
				)
				(justify left mirror)
			)
		)
		(fp_text user "-"
			(at -3.937762 0.241046 270)
			(unlocked yes)
			(layer "B.SilkS")
			(effects
				(font
					(size 1.905 1.4224)
					(thickness 0.1524)
				)
				(justify left mirror)
			)
		)
		(fp_text user "-"
			(at -3.937762 0.241046 270)
			(unlocked yes)
			(layer "B.Fab")
			(effects
				(font
					(size 1.905 1.4224)
					(thickness 0.1524)
				)
				(justify left mirror)
			)
		)
		(fp_text user "+"
			(at 3.29565 0.6858 0)
			(unlocked yes)
			(layer "B.Fab")
			(effects
				(font
					(size 1.905 1.4224)
					(thickness 0.1524)
				)
				(justify left mirror)
			)
		)
		(pad "A" smd rect
			(at 1.640078 0 270)
			(size 0.9906 1.2192)
			(layers "B.Cu" "B.Mask" "B.Paste")
			(net "P5V_AUX")
		)
		(pad "C" smd rect
			(at -1.640078 0 270)
			(size 0.9906 1.2192)
			(layers "B.Cu" "B.Mask" "B.Paste")
			(net "CRT_VCC5")
		)
	)
)
